# TIMECARD (Time Appliance Project (Time Card)) — schematic netlist excerpt (pin names and nets, part order shuffled) for the footprints in the layout excerpt that follows; sources: Cadence DE-HDL packaged netlist, KiCad conversion of R4006-B0001-02_R01.brd

SP2  SOLDER_PREFORM  pkg 0201_SOLDER_PREFORM_4MIL  page 28 : \1\ = SG ; \2\ = XP3R3V_AGND
R358  RESISTOR  10KOHM 1%  pkg SMC_0402R_H016  page 13 : \1\ = MHZ200CLKP_CLKIN ; \2\ = XP2R5V_FPGA

(kicad_pcb
	(version 20260206)
	(generator "pcbnew")
	(generator_version "10.0")
	(general
		(thickness 1.6)
		(legacy_teardrops no)
	)
	(paper "A4")
	(title_block
		(title "timecard-production-celestica-r4006 — R4006-B0001-02_R01.brd")
		(comment 1 "Time Appliance Project (Time Card) / footprints 1067-1068 of 1113")
	)
	(layers
		(0 "F.Cu" signal "TOP")
		(4 "In1.Cu" signal "L02_GND1")
		(6 "In2.Cu" signal "L03_SIG1")
		(8 "In3.Cu" signal "L04_GND2")
		(10 "In4.Cu" signal "L05_VCC1")
		(12 "In5.Cu" signal "L06_VCC2")
		(14 "In6.Cu" signal "L07_GND3")
		(16 "In7.Cu" signal "L08_SIG2")
		(18 "In8.Cu" signal "L09_GND4")
		(2 "B.Cu" signal "BOTTOM")
		(9 "F.Adhes" user "F.Adhesive")
		(11 "B.Adhes" user "B.Adhesive")
		(13 "F.Paste" user "Package Geometry/Pastemask Top")
		(15 "B.Paste" user "Package Geometry/Pastemask Bottom")
		(5 "F.SilkS" user "Ref Des/Silkscreen Top")
		(7 "B.SilkS" user "Ref Des/Silkscreen Bottom")
		(1 "F.Mask" user "Board Geometry/Soldermask Top")
		(3 "B.Mask" user "Board Geometry/Soldermask Bottom")
		(17 "Dwgs.User" user "User.Drawings")
		(19 "Cmts.User" user "User.Comments")
		(21 "Eco1.User" user "User.Eco1")
		(23 "Eco2.User" user "User.Eco2")
		(25 "Edge.Cuts" user "Board Geometry/Outline")
		(27 "Margin" user)
		(31 "F.CrtYd" user "Package Geometry/Place Bound Top")
		(29 "B.CrtYd" user "Package Geometry/Place Bound Bottom")
		(35 "F.Fab" user "Ref Des/Assembly Top")
		(33 "B.Fab" user "Ref Des/Assembly Bottom")
	)
	(footprint ""
		(layer "B.Cu")
		(at 85.5472 -100.2538 180)
		(property "Reference" "SP2"
			(at 0.8382 -1.74117 0)
			(unlocked yes)
			(layer "B.SilkS")
			(effects
				(font
					(size 0.7874 0.5842)
					(thickness 0.1524)
				)
				(justify mirror)
			)
		)
		(property "Value" ""
			(at 0 0 0)
			(layer "B.Fab")
			(effects
				(font
					(size 1.27 1.27)
				)
				(justify mirror)
			)
		)
		(duplicate_pad_numbers_are_jumpers no)
		(fp_rect
			(start 0.1778 -0.3048)
			(end -0.1778 0.3048)
			(stroke
				(width 0)
				(type default)
			)
			(fill yes)
			(layer "B.Paste")
		)
		(fp_rect
			(start 0.2286 -0.3556)
			(end -0.2286 0.3556)
			(stroke
				(width 0)
				(type default)
			)
			(fill no)
			(layer "B.CrtYd")
		)
		(fp_line
			(start 0.1397 0.2413)
			(end 0.1397 -0.2413)
			(stroke
				(width 0.1)
				(type default)
			)
			(layer "B.Fab")
		)
		(fp_line
			(start 0.1397 -0.2413)
			(end -0.1397 -0.2413)
			(stroke
				(width 0.1)
				(type default)
			)
			(layer "B.Fab")
		)
		(fp_line
			(start -0.1397 0.2413)
			(end 0.1397 0.2413)
			(stroke
				(width 0.1)
				(type default)
			)
			(layer "B.Fab")
		)
		(fp_line
			(start -0.1397 -0.2413)
			(end -0.1397 0.2413)
			(stroke
				(width 0.1)
				(type default)
			)
			(layer "B.Fab")
		)
		(pad "1" smd rect
			(at 0.1143 0)
			(size 0.127 0.6096)
			(layers "B.Cu" "B.Mask" "B.Paste")
			(net "SG")
		)
		(pad "2" smd rect
			(at -0.1143 0)
			(size 0.127 0.6096)
			(layers "B.Cu" "B.Mask" "B.Paste")
			(net "XP3R3V_AGND")
		)
	)
	(footprint ""
		(layer "B.Cu")
		(at 112.141 -27.94 90)
		(property "Reference" "R358"
			(at -2.667 -0.16637 270)
			(unlocked yes)
			(layer "B.SilkS")
			(effects
				(font
					(size 0.7874 0.5842)
					(thickness 0.1524)
				)
				(justify mirror)
			)
		)
		(property "Value" "VAL*"
			(at -0.02032 2.13233 90)
			(unlocked yes)
			(layer "B.Fab")
			(hide yes)
			(effects
				(font
					(size 0.7874 0.5842)
					(thickness 0.1524)
				)
				(justify mirror)
			)
		)
		(property "Tolerance" "TOL*"
			(at -0.044704 3.05435 90)
			(unlocked yes)
			(layer "Cmts.User")
			(hide yes)
			(effects
				(font
					(size 0.7874 0.5842)
					(thickness 0.1524)
				)
				(justify mirror)
			)
		)
		(property "User Part Number" "PARTNUM*"
			(at -0.02032 4.024884 90)
			(unlocked yes)
			(layer "Cmts.User")
			(hide yes)
			(effects
				(font
					(size 0.7874 0.5842)
					(thickness 0.1524)
				)
				(justify mirror)
			)
		)
		(property "Device Type" "RESISTOR-G155-11002-01,10KOHM,A"
			(at -0.008382 1.210564 90)
			(unlocked yes)
			(layer "B.Fab")
			(hide yes)
			(effects
				(font
					(size 0.7874 0.5842)
					(thickness 0.1524)
				)
				(justify mirror)
			)
		)
		(duplicate_pad_numbers_are_jumpers no)
		(fp_line
			(start 1.143 -0.5588)
			(end 1.143 0.5588)
			(stroke
				(width 0.1)
				(type default)
			)
			(layer "B.SilkS")
		)
		(fp_line
			(start -1.143 -0.5588)
			(end 1.143 -0.5588)
			(stroke
				(width 0.1)
				(type default)
			)
			(layer "B.SilkS")
		)
		(fp_line
			(start 1.143 0.5588)
			(end -1.143 0.5588)
			(stroke
				(width 0.1)
				(type default)
			)
			(layer "B.SilkS")
		)
		(fp_line
			(start -1.143 0.5588)
			(end -1.143 -0.5588)
			(stroke
				(width 0.1)
				(type default)
			)
			(layer "B.SilkS")
		)
		(fp_poly
			(pts
				(xy 1.143 0.5588) (xy -1.143 0.5588) (xy -1.143 -0.5588) (xy 1.143 -0.5588)
			)
			(stroke
				(width 0)
				(type default)
			)
			(fill no)
			(layer "B.CrtYd")
		)
		(fp_line
			(start 0.508 -0.3048)
			(end 0.508 0.3048)
			(stroke
				(width 0.1)
				(type default)
			)
			(layer "B.Fab")
		)
		(fp_line
			(start -0.508 -0.3048)
			(end 0.508 -0.3048)
			(stroke
				(width 0.1)
				(type default)
			)
			(layer "B.Fab")
		)
		(fp_line
			(start 0.508 0.3048)
			(end -0.508 0.3048)
			(stroke
				(width 0.1)
				(type default)
			)
			(layer "B.Fab")
		)
		(fp_line
			(start -0.508 0.3048)
			(end -0.508 -0.3048)
			(stroke
				(width 0.1)
				(type default)
			)
			(layer "B.Fab")
		)
		(pad "1" smd rect
			(at 0.5334 0 270)
			(size 0.7112 0.6096)
			(layers "B.Cu" "B.Mask" "B.Paste")
			(net "MHZ200CLKP_CLKIN")
		)
		(pad "2" smd rect
			(at -0.5334 0 270)
			(size 0.7112 0.6096)
			(layers "B.Cu" "B.Mask" "B.Paste")
			(net "XP2R5V_FPGA")
		)
		(zone
			(layer "B.Cu")
			(hatch none 0.5)
			(connect_pads
				(clearance 0)
			)
			(min_thickness 0.25)
			(keepout
				(tracks allowed)
				(vias not_allowed)
				(pads allowed)
				(copperpour not_allowed)
				(footprints allowed)
			)
			(placement
				(enabled no)
				(sheetname "")
			)
			(fill
				(thermal_gap 0.5)
				(thermal_bridge_width 0.5)
				(island_removal_mode 0)
			)
			(polygon
				(pts
					(xy 112.4458 -28.0162) (xy 111.8362 -28.0162) (xy 111.8362 -27.8638) (xy 112.4458 -27.8638)
				)
			)
		)
		(zone
			(layer "B.Cu")
			(hatch none 0.5)
			(connect_pads
				(clearance 0)
			)
			(min_thickness 0.25)
			(keepout
				(tracks not_allowed)
				(vias allowed)
				(pads allowed)
				(copperpour not_allowed)
				(footprints allowed)
			)
			(placement
				(enabled no)
				(sheetname "")
			)
			(fill
				(thermal_gap 0.5)
				(thermal_bridge_width 0.5)
				(island_removal_mode 0)
			)
			(polygon
				(pts
					(xy 112.4458 -28.0162) (xy 111.8362 -28.0162) (xy 111.8362 -27.8638) (xy 112.4458 -27.8638)
				)
			)
		)
	)
)
